# T6G (Grand Teton) — schematic netlist excerpt (pin names and nets, part order shuffled) for the footprints in the layout excerpt that follows; sources: Cadence DE-HDL packaged netlist, KiCad conversion of 04192023_DAF0TMB3IC0_F0TG_MB_C_brd_V02_OCP.brd

PC455  Q_CAPP  470UF 2.5V 20% EMPTY  pkg SMLF  page 222 : A = PVDDIO_P1 ; B = GND
C2196  Q_CAP  22UF 4V 20% X6S  pkg C0402  page 69 : A = PVDDCR_CPU0_P0 ; B = GND

(kicad_pcb
	(version 20260206)
	(generator "pcbnew")
	(generator_version "10.0")
	(general
		(thickness 1.6)
		(legacy_teardrops no)
	)
	(paper "A4")
	(title_block
		(title "04192023_DAF0TMB3IC0_F0TG_MB_C_brd_V02_OCP.brd")
		(comment 1 "Grand Teton / footprints 5524-5525 of 8354")
	)
	(layers
		(0 "F.Cu" signal "TOP")
		(4 "In1.Cu" signal "GND")
		(6 "In2.Cu" signal "IN1")
		(8 "In3.Cu" signal "GND1")
		(10 "In4.Cu" signal "IN2")
		(12 "In5.Cu" signal "GND2")
		(14 "In6.Cu" signal "IN3")
		(16 "In7.Cu" signal "GND3")
		(18 "In8.Cu" signal "VCC")
		(20 "In9.Cu" signal "VCC1")
		(22 "In10.Cu" signal "GND4")
		(24 "In11.Cu" signal "IN4")
		(26 "In12.Cu" signal "GND5")
		(28 "In13.Cu" signal "IN5")
		(30 "In14.Cu" signal "GND6")
		(32 "In15.Cu" signal "IN6")
		(34 "In16.Cu" signal "GND7")
		(2 "B.Cu" signal "BOTTOM")
		(9 "F.Adhes" user "F.Adhesive")
		(11 "B.Adhes" user "B.Adhesive")
		(13 "F.Paste" user "Package Geometry/Pastemask Top")
		(15 "B.Paste" user "Package Geometry/Pastemask Bottom")
		(5 "F.SilkS" user "Ref Des/Silkscreen Top")
		(7 "B.SilkS" user "Ref Des/Silkscreen Bottom")
		(1 "F.Mask" user "Board Geometry/Soldermask Top")
		(3 "B.Mask" user "Board Geometry/Soldermask Bottom")
		(17 "Dwgs.User" user "User.Drawings")
		(19 "Cmts.User" user "User.Comments")
		(21 "Eco1.User" user "User.Eco1")
		(23 "Eco2.User" user "User.Eco2")
		(25 "Edge.Cuts" user "Board Geometry/Outline")
		(27 "Margin" user)
		(31 "F.CrtYd" user "Package Geometry/Place Bound Top")
		(29 "B.CrtYd" user "Package Geometry/Place Bound Bottom")
		(35 "F.Fab" user "Ref Des/Assembly Top")
		(33 "B.Fab" user "Ref Des/Assembly Bottom")
	)
	(footprint ""
		(layer "B.Cu")
		(at 28.395676 -339.864954 -90)
		(property "Reference" "PC455"
			(at 9.410954 -0.914654 270)
			(unlocked yes)
			(layer "B.SilkS")
			(effects
				(font
					(size 0.7874 0.5842)
					(thickness 0.1524)
				)
				(justify left mirror)
			)
		)
		(property "Value" ""
			(at 0 0 90)
			(layer "B.Fab")
			(effects
				(font
					(size 1.27 1.27)
				)
				(justify mirror)
			)
		)
		(duplicate_pad_numbers_are_jumpers no)
		(fp_line
			(start -4.533392 2.249932)
			(end 4.533392 2.249932)
			(stroke
				(width 0.1524)
				(type default)
			)
			(layer "B.SilkS")
		)
		(fp_line
			(start 4.533392 2.249932)
			(end 4.533392 -2.249932)
			(stroke
				(width 0.1524)
				(type default)
			)
			(layer "B.SilkS")
		)
		(fp_line
			(start -4.533392 -2.249932)
			(end -4.533392 2.249932)
			(stroke
				(width 0.1524)
				(type default)
			)
			(layer "B.SilkS")
		)
		(fp_line
			(start 4.533392 -2.249932)
			(end -4.533392 -2.249932)
			(stroke
				(width 0.1524)
				(type default)
			)
			(layer "B.SilkS")
		)
		(fp_rect
			(start 5.39242 2.326132)
			(end 4.533392 -2.326132)
			(stroke
				(width 0)
				(type default)
			)
			(fill yes)
			(layer "B.SilkS")
		)
		(fp_line
			(start -3.750056 2.249932)
			(end 3.750056 2.249932)
			(stroke
				(width 0.1)
				(type default)
			)
			(layer "B.Fab")
		)
		(fp_line
			(start 3.750056 2.249932)
			(end 3.750056 -2.249932)
			(stroke
				(width 0.1)
				(type default)
			)
			(layer "B.Fab")
		)
		(fp_line
			(start -3.750056 -2.249932)
			(end -3.750056 2.249932)
			(stroke
				(width 0.1)
				(type default)
			)
			(layer "B.Fab")
		)
		(fp_line
			(start 3.750056 -2.249932)
			(end -3.750056 -2.249932)
			(stroke
				(width 0.1)
				(type default)
			)
			(layer "B.Fab")
		)
		(fp_text user "-"
			(at -4.602734 2.14122 270)
			(unlocked yes)
			(layer "B.SilkS")
			(effects
				(font
					(size 1.905 1.4224)
					(thickness 0.1524)
				)
				(justify left mirror)
			)
		)
		(fp_text user "+"
			(at 6.322314 0.786384 180)
			(unlocked yes)
			(layer "B.SilkS")
			(effects
				(font
					(size 1.905 1.4224)
					(thickness 0.1524)
				)
				(justify left mirror)
			)
		)
		(fp_text user "+"
			(at 6.322314 0.786384 180)
			(unlocked yes)
			(layer "B.Fab")
			(effects
				(font
					(size 1.905 1.4224)
					(thickness 0.1524)
				)
				(justify left mirror)
			)
		)
		(fp_text user "-"
			(at -4.8514 -0.14605 270)
			(unlocked yes)
			(layer "B.Fab")
			(effects
				(font
					(size 1.905 1.4224)
					(thickness 0.1524)
				)
				(justify left mirror)
			)
		)
		(pad "1" smd rect
			(at 3.199892 0 90)
			(size 2.413 2.8194)
			(layers "B.Cu" "B.Mask" "B.Paste")
			(net "PVDDIO_P1")
		)
		(pad "2" smd rect
			(at -3.199892 0 90)
			(size 2.413 2.8194)
			(layers "B.Cu" "B.Mask" "B.Paste")
			(net "GND")
		)
	)
	(footprint ""
		(layer "B.Cu")
		(at 361.645454 -250.25731)
		(property "Reference" "C2196"
			(at 0 0 0)
			(layer "B.SilkS")
			(hide yes)
			(effects
				(font
					(size 1.27 1.27)
				)
				(justify mirror)
			)
		)
		(property "Value" ""
			(at 0 0 0)
			(layer "B.Fab")
			(effects
				(font
					(size 1.27 1.27)
				)
				(justify mirror)
			)
		)
		(duplicate_pad_numbers_are_jumpers no)
		(fp_line
			(start -0.7874 -0.4064)
			(end -0.7874 0.4064)
			(stroke
				(width 0.1524)
				(type default)
			)
			(layer "B.SilkS")
		)
		(fp_line
			(start -0.7874 0.4064)
			(end 0.7874 0.4064)
			(stroke
				(width 0.1524)
				(type default)
			)
			(layer "B.SilkS")
		)
		(fp_line
			(start 0.7874 -0.4064)
			(end -0.7874 -0.4064)
			(stroke
				(width 0.1524)
				(type default)
			)
			(layer "B.SilkS")
		)
		(fp_line
			(start 0.7874 0.4064)
			(end 0.7874 -0.4064)
			(stroke
				(width 0.1524)
				(type default)
			)
			(layer "B.SilkS")
		)
		(fp_line
			(start -0.67945 -0.3048)
			(end -0.67945 0.3048)
			(stroke
				(width 0.1)
				(type default)
			)
			(layer "B.Fab")
		)
		(fp_line
			(start -0.67945 0.3048)
			(end -0.120396 0.3048)
			(stroke
				(width 0.1)
				(type default)
			)
			(layer "B.Fab")
		)
		(fp_line
			(start -0.12065 -0.3048)
			(end -0.67945 -0.3048)
			(stroke
				(width 0.1)
				(type default)
			)
			(layer "B.Fab")
		)
		(fp_line
			(start -0.12065 -0.2794)
			(end -0.12065 -0.3048)
			(stroke
				(width 0.1)
				(type default)
			)
			(layer "B.Fab")
		)
		(fp_line
			(start -0.120396 0.2794)
			(end 0.12065 0.2794)
			(stroke
				(width 0.1)
				(type default)
			)
			(layer "B.Fab")
		)
		(fp_line
			(start -0.120396 0.3048)
			(end -0.120396 0.2794)
			(stroke
				(width 0.1)
				(type default)
			)
			(layer "B.Fab")
		)
		(fp_line
			(start 0.12065 -0.305054)
			(end 0.12065 -0.2794)
			(stroke
				(width 0.1)
				(type default)
			)
			(layer "B.Fab")
		)
		(fp_line
			(start 0.12065 -0.2794)
			(end -0.12065 -0.2794)
			(stroke
				(width 0.1)
				(type default)
			)
			(layer "B.Fab")
		)
		(fp_line
			(start 0.12065 0.2794)
			(end 0.12065 0.3048)
			(stroke
				(width 0.1)
				(type default)
			)
			(layer "B.Fab")
		)
		(fp_line
			(start 0.12065 0.3048)
			(end 0.67945 0.3048)
			(stroke
				(width 0.1)
				(type default)
			)
			(layer "B.Fab")
		)
		(fp_line
			(start 0.67945 -0.305054)
			(end 0.12065 -0.305054)
			(stroke
				(width 0.1)
				(type default)
			)
			(layer "B.Fab")
		)
		(fp_line
			(start 0.67945 0.3048)
			(end 0.67945 -0.305054)
			(stroke
				(width 0.1)
				(type default)
			)
			(layer "B.Fab")
		)
		(pad "1" smd circle
			(at 0.40005 0 180)
			(size 0 0)
			(layers "B.Cu" "B.Mask" "B.Paste")
			(net "PVDDCR_CPU0_P0")
		)
		(pad "2" smd circle
			(at -0.40005 0 180)
			(size 0 0)
			(layers "B.Cu" "B.Mask" "B.Paste")
			(net "GND")
		)
	)
)
